# S9S_MB_2U (Grand Teton) — schematic netlist excerpt (pin names and nets, part order shuffled) for the footprints in the layout excerpt that follows; sources: Cadence DE-HDL packaged netlist, KiCad conversion of 03242023_DA0F0TMBIJ0_F0T_Motherboard_J_brd_V01_OCP.brd

R4789  Q_RES  10K 1% EMPTY  pkg 0402LF  page 307 : A = P3V3_AUX ; B = PWRGD_DSW_PWROK
R3390  Q_RES  49.9 1% CHIP  pkg 0402LF  page 149 : A = GPU_FPGA_BOOT_EN_BUF_R ; B = GPU_FPGA_BOOT_EN_BUF

(kicad_pcb
	(version 20260206)
	(generator "pcbnew")
	(generator_version "10.0")
	(general
		(thickness 1.6)
		(legacy_teardrops no)
	)
	(paper "A4")
	(title_block
		(title "03242023_DA0F0TMBIJ0_F0T_Motherboard_J_brd_V01_OCP.brd")
		(comment 1 "Grand Teton / footprints 1553-1554 of 6105")
	)
	(layers
		(0 "F.Cu" signal "TOP")
		(4 "In1.Cu" signal "GND")
		(6 "In2.Cu" signal "IN1")
		(8 "In3.Cu" signal "GND1")
		(10 "In4.Cu" signal "IN2")
		(12 "In5.Cu" signal "GND2")
		(14 "In6.Cu" signal "IN3")
		(16 "In7.Cu" signal "GND3")
		(18 "In8.Cu" signal "VCC")
		(20 "In9.Cu" signal "VCC1")
		(22 "In10.Cu" signal "GND4")
		(24 "In11.Cu" signal "IN4")
		(26 "In12.Cu" signal "GND5")
		(28 "In13.Cu" signal "IN5")
		(30 "In14.Cu" signal "GND6")
		(32 "In15.Cu" signal "IN6")
		(34 "In16.Cu" signal "GND7")
		(2 "B.Cu" signal "BOTTOM")
		(9 "F.Adhes" user "F.Adhesive")
		(11 "B.Adhes" user "B.Adhesive")
		(13 "F.Paste" user "Package Geometry/Pastemask Top")
		(15 "B.Paste" user "Package Geometry/Pastemask Bottom")
		(5 "F.SilkS" user "Ref Des/Silkscreen Top")
		(7 "B.SilkS" user "Ref Des/Silkscreen Bottom")
		(1 "F.Mask" user "Board Geometry/Soldermask Top")
		(3 "B.Mask" user "Board Geometry/Soldermask Bottom")
		(17 "Dwgs.User" user "User.Drawings")
		(19 "Cmts.User" user "User.Comments")
		(21 "Eco1.User" user "User.Eco1")
		(23 "Eco2.User" user "User.Eco2")
		(25 "Edge.Cuts" user "Board Geometry/Outline")
		(27 "Margin" user)
		(31 "F.CrtYd" user "Package Geometry/Place Bound Top")
		(29 "B.CrtYd" user "Package Geometry/Place Bound Bottom")
		(35 "F.Fab" user "Ref Des/Assembly Top")
		(33 "B.Fab" user "Ref Des/Assembly Bottom")
	)
	(footprint ""
		(layer "F.Cu")
		(at 312.42 -23.9268)
		(property "Reference" "R4789"
			(at 0 0 0)
			(layer "F.SilkS")
			(hide yes)
			(effects
				(font
					(size 1.27 1.27)
				)
			)
		)
		(property "Value" ""
			(at 0 0 0)
			(layer "F.Fab")
			(effects
				(font
					(size 1.27 1.27)
				)
			)
		)
		(duplicate_pad_numbers_are_jumpers no)
		(fp_line
			(start -0.7874 -0.4064)
			(end 0.7874 -0.4064)
			(stroke
				(width 0.1524)
				(type default)
			)
			(layer "F.SilkS")
		)
		(fp_line
			(start -0.7874 0.4064)
			(end -0.7874 -0.4064)
			(stroke
				(width 0.1524)
				(type default)
			)
			(layer "F.SilkS")
		)
		(fp_line
			(start 0.7874 -0.4064)
			(end 0.7874 0.4064)
			(stroke
				(width 0.1524)
				(type default)
			)
			(layer "F.SilkS")
		)
		(fp_line
			(start 0.7874 0.4064)
			(end -0.7874 0.4064)
			(stroke
				(width 0.1524)
				(type default)
			)
			(layer "F.SilkS")
		)
		(fp_line
			(start -0.67945 -0.305054)
			(end -0.12065 -0.305054)
			(stroke
				(width 0.1)
				(type default)
			)
			(layer "F.Fab")
		)
		(fp_line
			(start -0.67945 0.3048)
			(end -0.67945 -0.305054)
			(stroke
				(width 0.1)
				(type default)
			)
			(layer "F.Fab")
		)
		(fp_line
			(start -0.12065 -0.305054)
			(end -0.12065 -0.2794)
			(stroke
				(width 0.1)
				(type default)
			)
			(layer "F.Fab")
		)
		(fp_line
			(start -0.12065 -0.2794)
			(end 0.12065 -0.2794)
			(stroke
				(width 0.1)
				(type default)
			)
			(layer "F.Fab")
		)
		(fp_line
			(start -0.12065 0.2794)
			(end -0.12065 0.3048)
			(stroke
				(width 0.1)
				(type default)
			)
			(layer "F.Fab")
		)
		(fp_line
			(start -0.12065 0.3048)
			(end -0.67945 0.3048)
			(stroke
				(width 0.1)
				(type default)
			)
			(layer "F.Fab")
		)
		(fp_line
			(start 0.120396 0.2794)
			(end -0.12065 0.2794)
			(stroke
				(width 0.1)
				(type default)
			)
			(layer "F.Fab")
		)
		(fp_line
			(start 0.120396 0.3048)
			(end 0.120396 0.2794)
			(stroke
				(width 0.1)
				(type default)
			)
			(layer "F.Fab")
		)
		(fp_line
			(start 0.12065 -0.3048)
			(end 0.67945 -0.3048)
			(stroke
				(width 0.1)
				(type default)
			)
			(layer "F.Fab")
		)
		(fp_line
			(start 0.12065 -0.2794)
			(end 0.12065 -0.3048)
			(stroke
				(width 0.1)
				(type default)
			)
			(layer "F.Fab")
		)
		(fp_line
			(start 0.67945 -0.3048)
			(end 0.67945 0.3048)
			(stroke
				(width 0.1)
				(type default)
			)
			(layer "F.Fab")
		)
		(fp_line
			(start 0.67945 0.3048)
			(end 0.120396 0.3048)
			(stroke
				(width 0.1)
				(type default)
			)
			(layer "F.Fab")
		)
		(pad "1" smd circle
			(at -0.40005 0)
			(size 0 0)
			(layers "F.Cu" "F.Mask" "F.Paste")
			(net "P3V3_AUX")
		)
		(pad "2" smd circle
			(at 0.40005 0)
			(size 0 0)
			(layers "F.Cu" "F.Mask" "F.Paste")
			(net "PWRGD_DSW_PWROK")
		)
	)
	(footprint ""
		(layer "F.Cu")
		(at 170.23588 -437.987948)
		(property "Reference" "R3390"
			(at 0 0 0)
			(layer "F.SilkS")
			(hide yes)
			(effects
				(font
					(size 1.27 1.27)
				)
			)
		)
		(property "Value" ""
			(at 0 0 0)
			(layer "F.Fab")
			(effects
				(font
					(size 1.27 1.27)
				)
			)
		)
		(duplicate_pad_numbers_are_jumpers no)
		(fp_line
			(start -0.7874 -0.4064)
			(end 0.7874 -0.4064)
			(stroke
				(width 0.1524)
				(type default)
			)
			(layer "F.SilkS")
		)
		(fp_line
			(start -0.7874 0.4064)
			(end -0.7874 -0.4064)
			(stroke
				(width 0.1524)
				(type default)
			)
			(layer "F.SilkS")
		)
		(fp_line
			(start 0.7874 -0.4064)
			(end 0.7874 0.4064)
			(stroke
				(width 0.1524)
				(type default)
			)
			(layer "F.SilkS")
		)
		(fp_line
			(start 0.7874 0.4064)
			(end -0.7874 0.4064)
			(stroke
				(width 0.1524)
				(type default)
			)
			(layer "F.SilkS")
		)
		(fp_line
			(start -0.67945 -0.305054)
			(end -0.12065 -0.305054)
			(stroke
				(width 0.1)
				(type default)
			)
			(layer "F.Fab")
		)
		(fp_line
			(start -0.67945 0.3048)
			(end -0.67945 -0.305054)
			(stroke
				(width 0.1)
				(type default)
			)
			(layer "F.Fab")
		)
		(fp_line
			(start -0.12065 -0.305054)
			(end -0.12065 -0.2794)
			(stroke
				(width 0.1)
				(type default)
			)
			(layer "F.Fab")
		)
		(fp_line
			(start -0.12065 -0.2794)
			(end 0.12065 -0.2794)
			(stroke
				(width 0.1)
				(type default)
			)
			(layer "F.Fab")
		)
		(fp_line
			(start -0.12065 0.2794)
			(end -0.12065 0.3048)
			(stroke
				(width 0.1)
				(type default)
			)
			(layer "F.Fab")
		)
		(fp_line
			(start -0.12065 0.3048)
			(end -0.67945 0.3048)
			(stroke
				(width 0.1)
				(type default)
			)
			(layer "F.Fab")
		)
		(fp_line
			(start 0.120396 0.2794)
			(end -0.12065 0.2794)
			(stroke
				(width 0.1)
				(type default)
			)
			(layer "F.Fab")
		)
		(fp_line
			(start 0.120396 0.3048)
			(end 0.120396 0.2794)
			(stroke
				(width 0.1)
				(type default)
			)
			(layer "F.Fab")
		)
		(fp_line
			(start 0.12065 -0.3048)
			(end 0.67945 -0.3048)
			(stroke
				(width 0.1)
				(type default)
			)
			(layer "F.Fab")
		)
		(fp_line
			(start 0.12065 -0.2794)
			(end 0.12065 -0.3048)
			(stroke
				(width 0.1)
				(type default)
			)
			(layer "F.Fab")
		)
		(fp_line
			(start 0.67945 -0.3048)
			(end 0.67945 0.3048)
			(stroke
				(width 0.1)
				(type default)
			)
			(layer "F.Fab")
		)
		(fp_line
			(start 0.67945 0.3048)
			(end 0.120396 0.3048)
			(stroke
				(width 0.1)
				(type default)
			)
			(layer "F.Fab")
		)
		(pad "1" smd circle
			(at -0.40005 0)
			(size 0 0)
			(layers "F.Cu" "F.Mask" "F.Paste")
			(net "GPU_FPGA_BOOT_EN_BUF_R")
		)
		(pad "2" smd circle
			(at 0.40005 0)
			(size 0 0)
			(layers "F.Cu" "F.Mask" "F.Paste")
			(net "GPU_FPGA_BOOT_EN_BUF")
		)
	)
)
